(kicad_pcb
	(version 20260206)
	(generator "pcbnew")
	(generator_version "10.0")
	(general
		(thickness 1.6)
		(legacy_teardrops no)
	)
	(paper "A4")
	(title_block
		(title "01162023_DA0F0TEBIF0_F0T_Expander_BD_F_brd_V02_OCP.brd")
		(comment 1 "Grand Teton / footprints 9601-9607 of 9728")
	)
	(layers
		(0 "F.Cu" signal "TOP")
		(4 "In1.Cu" signal "GND")
		(6 "In2.Cu" signal "VCC")
		(8 "In3.Cu" signal "VCC1")
		(10 "In4.Cu" signal "GND1")
		(12 "In5.Cu" signal "IN1")
		(14 "In6.Cu" signal "GND2")
		(16 "In7.Cu" signal "IN2")
		(18 "In8.Cu" signal "GND3")
		(20 "In9.Cu" signal "IN3")
		(22 "In10.Cu" signal "GND4")
		(24 "In11.Cu" signal "IN4")
		(26 "In12.Cu" signal "GND5")
		(28 "In13.Cu" signal "IN5")
		(30 "In14.Cu" signal "GND6")
		(32 "In15.Cu" signal "IN6")
		(34 "In16.Cu" signal "GND7")
		(2 "B.Cu" signal "BOTTOM")
		(9 "F.Adhes" user "F.Adhesive")
		(11 "B.Adhes" user "B.Adhesive")
		(13 "F.Paste" user "Package Geometry/Pastemask Top")
		(15 "B.Paste" user "Package Geometry/Pastemask Bottom")
		(5 "F.SilkS" user "Ref Des/Silkscreen Top")
		(7 "B.SilkS" user "Ref Des/Silkscreen Bottom")
		(1 "F.Mask" user "Board Geometry/Soldermask Top")
		(3 "B.Mask" user "Board Geometry/Soldermask Bottom")
		(17 "Dwgs.User" user "User.Drawings")
		(19 "Cmts.User" user "User.Comments")
		(21 "Eco1.User" user "User.Eco1")
		(23 "Eco2.User" user "User.Eco2")
		(25 "Edge.Cuts" user "Board Geometry/Outline")
		(27 "Margin" user)
		(31 "F.CrtYd" user "Package Geometry/Place Bound Top")
		(29 "B.CrtYd" user "Package Geometry/Place Bound Bottom")
		(35 "F.Fab" user "Ref Des/Assembly Top")
		(33 "B.Fab" user "Ref Des/Assembly Bottom")
	)
	(footprint ""
		(layer "B.Cu")
		(at 267.087858 -366.778794 -90)
		(property "Reference" "PC6002"
			(at 0 0 90)
			(layer "B.SilkS")
			(hide yes)
			(effects
				(font
					(size 1.27 1.27)
				)
				(justify mirror)
			)
		)
		(property "Value" ""
			(at 0 0 90)
			(layer "B.Fab")
			(effects
				(font
					(size 1.27 1.27)
				)
				(justify mirror)
			)
		)
		(duplicate_pad_numbers_are_jumpers no)
		(fp_line
			(start -0.7874 0.4064)
			(end 0.7874 0.4064)
			(stroke
				(width 0.1524)
				(type default)
			)
			(layer "B.SilkS")
		)
		(fp_line
			(start 0.7874 0.4064)
			(end 0.7874 -0.4064)
			(stroke
				(width 0.1524)
				(type default)
			)
			(layer "B.SilkS")
		)
		(fp_line
			(start -0.7874 -0.4064)
			(end -0.7874 0.4064)
			(stroke
				(width 0.1524)
				(type default)
			)
			(layer "B.SilkS")
		)
		(fp_line
			(start 0.7874 -0.4064)
			(end -0.7874 -0.4064)
			(stroke
				(width 0.1524)
				(type default)
			)
			(layer "B.SilkS")
		)
		(fp_line
			(start -0.67945 0.3048)
			(end -0.120396 0.3048)
			(stroke
				(width 0.1)
				(type default)
			)
			(layer "B.Fab")
		)
		(fp_line
			(start -0.120396 0.3048)
			(end -0.120396 0.2794)
			(stroke
				(width 0.1)
				(type default)
			)
			(layer "B.Fab")
		)
		(fp_line
			(start 0.12065 0.3048)
			(end 0.67945 0.3048)
			(stroke
				(width 0.1)
				(type default)
			)
			(layer "B.Fab")
		)
		(fp_line
			(start 0.67945 0.3048)
			(end 0.67945 -0.305054)
			(stroke
				(width 0.1)
				(type default)
			)
			(layer "B.Fab")
		)
		(fp_line
			(start -0.120396 0.2794)
			(end 0.12065 0.2794)
			(stroke
				(width 0.1)
				(type default)
			)
			(layer "B.Fab")
		)
		(fp_line
			(start 0.12065 0.2794)
			(end 0.12065 0.3048)
			(stroke
				(width 0.1)
				(type default)
			)
			(layer "B.Fab")
		)
		(fp_line
			(start -0.12065 -0.2794)
			(end -0.12065 -0.3048)
			(stroke
				(width 0.1)
				(type default)
			)
			(layer "B.Fab")
		)
		(fp_line
			(start 0.12065 -0.2794)
			(end -0.12065 -0.2794)
			(stroke
				(width 0.1)
				(type default)
			)
			(layer "B.Fab")
		)
		(fp_line
			(start -0.67945 -0.3048)
			(end -0.67945 0.3048)
			(stroke
				(width 0.1)
				(type default)
			)
			(layer "B.Fab")
		)
		(fp_line
			(start -0.12065 -0.3048)
			(end -0.67945 -0.3048)
			(stroke
				(width 0.1)
				(type default)
			)
			(layer "B.Fab")
		)
		(fp_line
			(start 0.12065 -0.305054)
			(end 0.12065 -0.2794)
			(stroke
				(width 0.1)
				(type default)
			)
			(layer "B.Fab")
		)
		(fp_line
			(start 0.67945 -0.305054)
			(end 0.12065 -0.305054)
			(stroke
				(width 0.1)
				(type default)
			)
			(layer "B.Fab")
		)
		(pad "1" smd circle
			(at 0.40005 0 90)
			(size 0 0)
			(layers "B.Cu" "B.Mask" "B.Paste")
			(net "P12V_HSC_GATE_RC")
		)
		(pad "2" smd circle
			(at -0.40005 0 90)
			(size 0 0)
			(layers "B.Cu" "B.Mask" "B.Paste")
			(net "P12V_HSC_GATE2")
		)
	)
	(footprint ""
		(layer "B.Cu")
		(at 66.7766 -293.99992 90)
		(property "Reference" "C1166"
			(at 0 0 90)
			(layer "B.SilkS")
			(hide yes)
			(effects
				(font
					(size 1.27 1.27)
				)
				(justify mirror)
			)
		)
		(property "Value" ""
			(at 0 0 90)
			(layer "B.Fab")
			(effects
				(font
					(size 1.27 1.27)
				)
				(justify mirror)
			)
		)
		(duplicate_pad_numbers_are_jumpers no)
		(fp_line
			(start 0.299974 -0.150114)
			(end -0.299974 -0.150114)
			(stroke
				(width 0.1)
				(type default)
			)
			(layer "B.Fab")
		)
		(fp_line
			(start -0.299974 -0.150114)
			(end -0.299974 0.150114)
			(stroke
				(width 0.1)
				(type default)
			)
			(layer "B.Fab")
		)
		(fp_line
			(start 0.299974 0.150114)
			(end 0.299974 -0.150114)
			(stroke
				(width 0.1)
				(type default)
			)
			(layer "B.Fab")
		)
		(fp_line
			(start -0.299974 0.150114)
			(end 0.299974 0.150114)
			(stroke
				(width 0.1)
				(type default)
			)
			(layer "B.Fab")
		)
		(pad "1" smd rect
			(at 0.2667 0 270)
			(size 0.3048 0.381)
			(layers "B.Cu" "B.Mask" "B.Paste")
			(net "P0V8_SERDES_VDDA_PEX0")
		)
		(pad "2" smd rect
			(at -0.2667 0 270)
			(size 0.3048 0.381)
			(layers "B.Cu" "B.Mask" "B.Paste")
			(net "GND")
		)
	)
	(footprint ""
		(layer "B.Cu")
		(at 46.1264 -140.8176 180)
		(property "Reference" "C852"
			(at 0 0 0)
			(layer "B.SilkS")
			(hide yes)
			(effects
				(font
					(size 1.27 1.27)
				)
				(justify mirror)
			)
		)
		(property "Value" ""
			(at 0 0 0)
			(layer "B.Fab")
			(effects
				(font
					(size 1.27 1.27)
				)
				(justify mirror)
			)
		)
		(duplicate_pad_numbers_are_jumpers no)
		(fp_line
			(start 0.7874 0.4064)
			(end 0.7874 -0.4064)
			(stroke
				(width 0.1524)
				(type default)
			)
			(layer "B.SilkS")
		)
		(fp_line
			(start 0.7874 -0.4064)
			(end -0.7874 -0.4064)
			(stroke
				(width 0.1524)
				(type default)
			)
			(layer "B.SilkS")
		)
		(fp_line
			(start -0.7874 0.4064)
			(end 0.7874 0.4064)
			(stroke
				(width 0.1524)
				(type default)
			)
			(layer "B.SilkS")
		)
		(fp_line
			(start -0.7874 -0.4064)
			(end -0.7874 0.4064)
			(stroke
				(width 0.1524)
				(type default)
			)
			(layer "B.SilkS")
		)
		(fp_line
			(start 0.67945 0.3048)
			(end 0.67945 -0.305054)
			(stroke
				(width 0.1)
				(type default)
			)
			(layer "B.Fab")
		)
		(fp_line
			(start 0.67945 -0.305054)
			(end 0.12065 -0.305054)
			(stroke
				(width 0.1)
				(type default)
			)
			(layer "B.Fab")
		)
		(fp_line
			(start 0.12065 0.3048)
			(end 0.67945 0.3048)
			(stroke
				(width 0.1)
				(type default)
			)
			(layer "B.Fab")
		)
		(fp_line
			(start 0.12065 0.2794)
			(end 0.12065 0.3048)
			(stroke
				(width 0.1)
				(type default)
			)
			(layer "B.Fab")
		)
		(fp_line
			(start 0.12065 -0.2794)
			(end -0.12065 -0.2794)
			(stroke
				(width 0.1)
				(type default)
			)
			(layer "B.Fab")
		)
		(fp_line
			(start 0.12065 -0.305054)
			(end 0.12065 -0.2794)
			(stroke
				(width 0.1)
				(type default)
			)
			(layer "B.Fab")
		)
		(fp_line
			(start -0.120396 0.3048)
			(end -0.120396 0.2794)
			(stroke
				(width 0.1)
				(type default)
			)
			(layer "B.Fab")
		)
		(fp_line
			(start -0.120396 0.2794)
			(end 0.12065 0.2794)
			(stroke
				(width 0.1)
				(type default)
			)
			(layer "B.Fab")
		)
		(fp_line
			(start -0.12065 -0.2794)
			(end -0.12065 -0.3048)
			(stroke
				(width 0.1)
				(type default)
			)
			(layer "B.Fab")
		)
		(fp_line
			(start -0.12065 -0.3048)
			(end -0.67945 -0.3048)
			(stroke
				(width 0.1)
				(type default)
			)
			(layer "B.Fab")
		)
		(fp_line
			(start -0.67945 0.3048)
			(end -0.120396 0.3048)
			(stroke
				(width 0.1)
				(type default)
			)
			(layer "B.Fab")
		)
		(fp_line
			(start -0.67945 -0.3048)
			(end -0.67945 0.3048)
			(stroke
				(width 0.1)
				(type default)
			)
			(layer "B.Fab")
		)
		(pad "1" smd circle
			(at 0.40005 0)
			(size 0 0)
			(layers "B.Cu" "B.Mask" "B.Paste")
			(net "P3V3_NIC0")
		)
		(pad "2" smd circle
			(at -0.40005 0)
			(size 0 0)
			(layers "B.Cu" "B.Mask" "B.Paste")
			(net "GND")
		)
	)
	(footprint ""
		(layer "B.Cu")
		(at 375.58853 -237.572296 180)
		(property "Reference" "R913"
			(at 0 0 0)
			(layer "B.SilkS")
			(hide yes)
			(effects
				(font
					(size 1.27 1.27)
				)
				(justify mirror)
			)
		)
		(property "Value" ""
			(at 0 0 0)
			(layer "B.Fab")
			(effects
				(font
					(size 1.27 1.27)
				)
				(justify mirror)
			)
		)
		(duplicate_pad_numbers_are_jumpers no)
		(fp_line
			(start 0.7874 0.4064)
			(end 0.7874 -0.4064)
			(stroke
				(width 0.1524)
				(type default)
			)
			(layer "B.SilkS")
		)
		(fp_line
			(start 0.7874 -0.4064)
			(end -0.7874 -0.4064)
			(stroke
				(width 0.1524)
				(type default)
			)
			(layer "B.SilkS")
		)
		(fp_line
			(start -0.7874 0.4064)
			(end 0.7874 0.4064)
			(stroke
				(width 0.1524)
				(type default)
			)
			(layer "B.SilkS")
		)
		(fp_line
			(start -0.7874 -0.4064)
			(end -0.7874 0.4064)
			(stroke
				(width 0.1524)
				(type default)
			)
			(layer "B.SilkS")
		)
		(fp_line
			(start 0.67945 0.3048)
			(end 0.67945 -0.305054)
			(stroke
				(width 0.1)
				(type default)
			)
			(layer "B.Fab")
		)
		(fp_line
			(start 0.67945 -0.305054)
			(end 0.12065 -0.305054)
			(stroke
				(width 0.1)
				(type default)
			)
			(layer "B.Fab")
		)
		(fp_line
			(start 0.12065 0.3048)
			(end 0.67945 0.3048)
			(stroke
				(width 0.1)
				(type default)
			)
			(layer "B.Fab")
		)
		(fp_line
			(start 0.12065 0.2794)
			(end 0.12065 0.3048)
			(stroke
				(width 0.1)
				(type default)
			)
			(layer "B.Fab")
		)
		(fp_line
			(start 0.12065 -0.2794)
			(end -0.12065 -0.2794)
			(stroke
				(width 0.1)
				(type default)
			)
			(layer "B.Fab")
		)
		(fp_line
			(start 0.12065 -0.305054)
			(end 0.12065 -0.2794)
			(stroke
				(width 0.1)
				(type default)
			)
			(layer "B.Fab")
		)
		(fp_line
			(start -0.120396 0.3048)
			(end -0.120396 0.2794)
			(stroke
				(width 0.1)
				(type default)
			)
			(layer "B.Fab")
		)
		(fp_line
			(start -0.120396 0.2794)
			(end 0.12065 0.2794)
			(stroke
				(width 0.1)
				(type default)
			)
			(layer "B.Fab")
		)
		(fp_line
			(start -0.12065 -0.2794)
			(end -0.12065 -0.3048)
			(stroke
				(width 0.1)
				(type default)
			)
			(layer "B.Fab")
		)
		(fp_line
			(start -0.12065 -0.3048)
			(end -0.67945 -0.3048)
			(stroke
				(width 0.1)
				(type default)
			)
			(layer "B.Fab")
		)
		(fp_line
			(start -0.67945 0.3048)
			(end -0.120396 0.3048)
			(stroke
				(width 0.1)
				(type default)
			)
			(layer "B.Fab")
		)
		(fp_line
			(start -0.67945 -0.3048)
			(end -0.67945 0.3048)
			(stroke
				(width 0.1)
				(type default)
			)
			(layer "B.Fab")
		)
		(pad "1" smd circle
			(at 0.40005 0)
			(size 0 0)
			(layers "B.Cu" "B.Mask" "B.Paste")
			(net "FT4232_SDB_EEPROM_R_SCL")
		)
		(pad "2" smd circle
			(at -0.40005 0)
			(size 0 0)
			(layers "B.Cu" "B.Mask" "B.Paste")
			(net "FT4232_SDB_EEPROM_SCL")
		)
	)
	(footprint ""
		(layer "B.Cu")
		(at 344.297 -207.772 -90)
		(property "Reference" "R4147"
			(at 0 0 90)
			(layer "B.SilkS")
			(hide yes)
			(effects
				(font
					(size 1.27 1.27)
				)
				(justify mirror)
			)
		)
		(property "Value" ""
			(at 0 0 90)
			(layer "B.Fab")
			(effects
				(font
					(size 1.27 1.27)
				)
				(justify mirror)
			)
		)
		(duplicate_pad_numbers_are_jumpers no)
		(fp_line
			(start -0.7874 0.4064)
			(end 0.7874 0.4064)
			(stroke
				(width 0.1524)
				(type default)
			)
			(layer "B.SilkS")
		)
		(fp_line
			(start 0.7874 0.4064)
			(end 0.7874 -0.4064)
			(stroke
				(width 0.1524)
				(type default)
			)
			(layer "B.SilkS")
		)
		(fp_line
			(start -0.7874 -0.4064)
			(end -0.7874 0.4064)
			(stroke
				(width 0.1524)
				(type default)
			)
			(layer "B.SilkS")
		)
		(fp_line
			(start 0.7874 -0.4064)
			(end -0.7874 -0.4064)
			(stroke
				(width 0.1524)
				(type default)
			)
			(layer "B.SilkS")
		)
		(fp_line
			(start -0.67945 0.3048)
			(end -0.120396 0.3048)
			(stroke
				(width 0.1)
				(type default)
			)
			(layer "B.Fab")
		)
		(fp_line
			(start -0.120396 0.3048)
			(end -0.120396 0.2794)
			(stroke
				(width 0.1)
				(type default)
			)
			(layer "B.Fab")
		)
		(fp_line
			(start 0.12065 0.3048)
			(end 0.67945 0.3048)
			(stroke
				(width 0.1)
				(type default)
			)
			(layer "B.Fab")
		)
		(fp_line
			(start 0.67945 0.3048)
			(end 0.67945 -0.305054)
			(stroke
				(width 0.1)
				(type default)
			)
			(layer "B.Fab")
		)
		(fp_line
			(start -0.120396 0.2794)
			(end 0.12065 0.2794)
			(stroke
				(width 0.1)
				(type default)
			)
			(layer "B.Fab")
		)
		(fp_line
			(start 0.12065 0.2794)
			(end 0.12065 0.3048)
			(stroke
				(width 0.1)
				(type default)
			)
			(layer "B.Fab")
		)
		(fp_line
			(start -0.12065 -0.2794)
			(end -0.12065 -0.3048)
			(stroke
				(width 0.1)
				(type default)
			)
			(layer "B.Fab")
		)
		(fp_line
			(start 0.12065 -0.2794)
			(end -0.12065 -0.2794)
			(stroke
				(width 0.1)
				(type default)
			)
			(layer "B.Fab")
		)
		(fp_line
			(start -0.67945 -0.3048)
			(end -0.67945 0.3048)
			(stroke
				(width 0.1)
				(type default)
			)
			(layer "B.Fab")
		)
		(fp_line
			(start -0.12065 -0.3048)
			(end -0.67945 -0.3048)
			(stroke
				(width 0.1)
				(type default)
			)
			(layer "B.Fab")
		)
		(fp_line
			(start 0.12065 -0.305054)
			(end 0.12065 -0.2794)
			(stroke
				(width 0.1)
				(type default)
			)
			(layer "B.Fab")
		)
		(fp_line
			(start 0.67945 -0.305054)
			(end 0.12065 -0.305054)
			(stroke
				(width 0.1)
				(type default)
			)
			(layer "B.Fab")
		)
		(pad "1" smd circle
			(at 0.40005 0 90)
			(size 0 0)
			(layers "B.Cu" "B.Mask" "B.Paste")
			(net "PRSNT_SSD0_FPGA_R_N")
		)
		(pad "2" smd circle
			(at -0.40005 0 90)
			(size 0 0)
			(layers "B.Cu" "B.Mask" "B.Paste")
			(net "PRSNT_SSD0_FPGA_N")
		)
	)
	(footprint ""
		(layer "B.Cu")
		(at 343.449402 -308.613556 90)
		(property "Reference" "PR12"
			(at 0 0 90)
			(layer "B.SilkS")
			(hide yes)
			(effects
				(font
					(size 1.27 1.27)
				)
				(justify mirror)
			)
		)
		(property "Value" ""
			(at 0 0 90)
			(layer "B.Fab")
			(effects
				(font
					(size 1.27 1.27)
				)
				(justify mirror)
			)
		)
		(duplicate_pad_numbers_are_jumpers no)
		(fp_line
			(start 1.2954 -0.5842)
			(end -1.2954 -0.5842)
			(stroke
				(width 0.1524)
				(type default)
			)
			(layer "B.SilkS")
		)
		(fp_line
			(start -1.2954 -0.5842)
			(end -1.2954 0.5842)
			(stroke
				(width 0.1524)
				(type default)
			)
			(layer "B.SilkS")
		)
		(fp_line
			(start 1.2954 0.5842)
			(end 1.2954 -0.5842)
			(stroke
				(width 0.1524)
				(type default)
			)
			(layer "B.SilkS")
		)
		(fp_line
			(start -1.2954 0.5842)
			(end 1.2954 0.5842)
			(stroke
				(width 0.1524)
				(type default)
			)
			(layer "B.SilkS")
		)
		(fp_line
			(start 0.8636 -0.4572)
			(end -0.8636 -0.4572)
			(stroke
				(width 0.1)
				(type default)
			)
			(layer "B.Fab")
		)
		(fp_line
			(start -0.8636 -0.4572)
			(end -0.8636 -0.406654)
			(stroke
				(width 0.1)
				(type default)
			)
			(layer "B.Fab")
		)
		(fp_line
			(start 1.1938 -0.406654)
			(end 0.8636 -0.406654)
			(stroke
				(width 0.1)
				(type default)
			)
			(layer "B.Fab")
		)
		(fp_line
			(start 0.8636 -0.406654)
			(end 0.8636 -0.4572)
			(stroke
				(width 0.1)
				(type default)
			)
			(layer "B.Fab")
		)
		(fp_line
			(start -0.8636 -0.406654)
			(end -1.1938 -0.406654)
			(stroke
				(width 0.1)
				(type default)
			)
			(layer "B.Fab")
		)
		(fp_line
			(start -1.1938 -0.406654)
			(end -1.1938 0.4064)
			(stroke
				(width 0.1)
				(type default)
			)
			(layer "B.Fab")
		)
		(fp_line
			(start 1.1938 0.4064)
			(end 1.1938 -0.406654)
			(stroke
				(width 0.1)
				(type default)
			)
			(layer "B.Fab")
		)
		(fp_line
			(start 0.8636 0.4064)
			(end 1.1938 0.4064)
			(stroke
				(width 0.1)
				(type default)
			)
			(layer "B.Fab")
		)
		(fp_line
			(start -0.8636 0.4064)
			(end -0.8636 0.4572)
			(stroke
				(width 0.1)
				(type default)
			)
			(layer "B.Fab")
		)
		(fp_line
			(start -1.1938 0.4064)
			(end -0.8636 0.4064)
			(stroke
				(width 0.1)
				(type default)
			)
			(layer "B.Fab")
		)
		(fp_line
			(start 0.8636 0.4318)
			(end 0.8636 0.4064)
			(stroke
				(width 0.1)
				(type default)
			)
			(layer "B.Fab")
		)
		(fp_line
			(start 0.8636 0.4572)
			(end 0.8636 0.4318)
			(stroke
				(width 0.1)
				(type default)
			)
			(layer "B.Fab")
		)
		(fp_line
			(start -0.8636 0.4572)
			(end 0.8636 0.4572)
			(stroke
				(width 0.1)
				(type default)
			)
			(layer "B.Fab")
		)
		(pad "1" smd rect
			(at 0.7366 0)
			(size 0.7112 0.8128)
			(layers "B.Cu" "B.Mask" "B.Paste")
			(net "P0V8_PEX2")
		)
		(pad "2" smd rect
			(at -0.7366 0)
			(size 0.7112 0.8128)
			(layers "B.Cu" "B.Mask" "B.Paste")
			(net "GND")
		)
	)
	(footprint ""
		(layer "B.Cu")
		(at 402.249894 -299.699934 -90)
		(property "Reference" "C1972"
			(at 0 0 90)
			(layer "B.SilkS")
			(hide yes)
			(effects
				(font
					(size 1.27 1.27)
				)
				(justify mirror)
			)
		)
		(property "Value" ""
			(at 0 0 90)
			(layer "B.Fab")
			(effects
				(font
					(size 1.27 1.27)
				)
				(justify mirror)
			)
		)
		(duplicate_pad_numbers_are_jumpers no)
		(fp_line
			(start -0.299974 0.150114)
			(end 0.299974 0.150114)
			(stroke
				(width 0.1)
				(type default)
			)
			(layer "B.Fab")
		)
		(fp_line
			(start 0.299974 0.150114)
			(end 0.299974 -0.150114)
			(stroke
				(width 0.1)
				(type default)
			)
			(layer "B.Fab")
		)
		(fp_line
			(start -0.299974 -0.150114)
			(end -0.299974 0.150114)
			(stroke
				(width 0.1)
				(type default)
			)
			(layer "B.Fab")
		)
		(fp_line
			(start 0.299974 -0.150114)
			(end -0.299974 -0.150114)
			(stroke
				(width 0.1)
				(type default)
			)
			(layer "B.Fab")
		)
		(pad "1" smd rect
			(at 0.2667 0 90)
			(size 0.3048 0.381)
			(layers "B.Cu" "B.Mask" "B.Paste")
			(net "P0V8_SERDES_VDDA_PEX3")
		)
		(pad "2" smd rect
			(at -0.2667 0 90)
			(size 0.3048 0.381)
			(layers "B.Cu" "B.Mask" "B.Paste")
			(net "GND")
		)
	)
)
